(kicad_pcb
	(version 20260206)
	(generator "pcbnew")
	(generator_version "10.0")
	(general
		(thickness 1.6)
		(legacy_teardrops no)
	)
	(paper "A4")
	(title_block
		(title "12092022_DA0F0TMDCD0_F0T_Management_Board_D_brd_V3_OCP.brd")
		(comment 1 "Grand Teton / footprint 124 of 1440 (U5), pads 447-562 of 624")
	)
	(layers
		(0 "F.Cu" signal "TOP")
		(4 "In1.Cu" signal "GND")
		(6 "In2.Cu" signal "IN1")
		(8 "In3.Cu" signal "GND1")
		(10 "In4.Cu" signal "IN2")
		(12 "In5.Cu" signal "VCC")
		(14 "In6.Cu" signal "VCC1")
		(16 "In7.Cu" signal "IN3")
		(18 "In8.Cu" signal "GND2")
		(20 "In9.Cu" signal "IN4")
		(22 "In10.Cu" signal "GND3")
		(2 "B.Cu" signal "BOTTOM")
		(9 "F.Adhes" user "F.Adhesive")
		(11 "B.Adhes" user "B.Adhesive")
		(13 "F.Paste" user "Package Geometry/Pastemask Top")
		(15 "B.Paste" user "Package Geometry/Pastemask Bottom")
		(5 "F.SilkS" user "Ref Des/Silkscreen Top")
		(7 "B.SilkS" user "Ref Des/Silkscreen Bottom")
		(1 "F.Mask" user "Board Geometry/Soldermask Top")
		(3 "B.Mask" user "Board Geometry/Soldermask Bottom")
		(17 "Dwgs.User" user "User.Drawings")
		(19 "Cmts.User" user "User.Comments")
		(21 "Eco1.User" user "User.Eco1")
		(23 "Eco2.User" user "User.Eco2")
		(25 "Edge.Cuts" user "Board Geometry/Outline")
		(27 "Margin" user)
		(31 "F.CrtYd" user "Package Geometry/Place Bound Top")
		(29 "B.CrtYd" user "Package Geometry/Place Bound Bottom")
		(35 "F.Fab" user "Ref Des/Assembly Top")
		(33 "B.Fab" user "Ref Des/Assembly Bottom")
	)
	(footprint ""
		(layer "F.Cu")
		(at 54.894988 -49.37125 180)
		(property "Reference" "U5"
			(at -11.094212 -12.07262 0)
			(unlocked yes)
			(layer "F.SilkS")
			(effects
				(font
					(size 0.7874 0.5842)
					(thickness 0.1524)
				)
				(justify left)
			)
		)
		(property "Value" ""
			(at 0 0 180)
			(layer "F.Fab")
			(effects
				(font
					(size 1.27 1.27)
				)
			)
		)
		(duplicate_pad_numbers_are_jumpers no)
		(pad "N3" smd circle
			(at -8.400034 -0.40005 180)
			(size 0.4064 0.4064)
			(layers "F.Cu" "F.Mask" "F.Paste")
			(net "M_BMC_DDR4_MDM0")
		)
		(pad "N4" smd circle
			(at -7.599934 -0.40005 180)
			(size 0.4064 0.4064)
			(layers "F.Cu" "F.Mask" "F.Paste")
			(net "M_BMC_DDR4_ALERT_N")
		)
		(pad "N5" smd circle
			(at -6.800088 -0.40005 180)
			(size 0.4064 0.4064)
			(layers "F.Cu" "F.Mask" "F.Paste")
			(net "P1V8_STBY_AVDDPLL")
		)
		(pad "N6" smd circle
			(at -5.999988 -0.40005 180)
			(size 0.4064 0.4064)
			(layers "F.Cu" "F.Mask" "F.Paste")
			(net "GND")
		)
		(pad "N8" smd circle
			(at -4.400042 -0.40005 180)
			(size 0.4064 0.4064)
			(layers "F.Cu" "F.Mask" "F.Paste")
			(net "P1V0_AUX")
		)
		(pad "N9" smd circle
			(at -3.599942 -0.40005 180)
			(size 0.4064 0.4064)
			(layers "F.Cu" "F.Mask" "F.Paste")
			(net "GND")
		)
		(pad "N10" smd circle
			(at -2.800096 -0.40005 180)
			(size 0.4064 0.4064)
			(layers "F.Cu" "F.Mask" "F.Paste")
			(net "GND")
		)
		(pad "N11" smd circle
			(at -1.999996 -0.40005 180)
			(size 0.4064 0.4064)
			(layers "F.Cu" "F.Mask" "F.Paste")
			(net "P1V0_AUX")
		)
		(pad "N12" smd circle
			(at -1.199896 -0.40005 180)
			(size 0.4064 0.4064)
			(layers "F.Cu" "F.Mask" "F.Paste")
			(net "P1V8_AUX")
		)
		(pad "N13" smd circle
			(at -0.40005 -0.40005 180)
			(size 0.4064 0.4064)
			(layers "F.Cu" "F.Mask" "F.Paste")
			(net "P1V8_AUX")
		)
		(pad "N14" smd circle
			(at 0.40005 -0.40005 180)
			(size 0.4064 0.4064)
			(layers "F.Cu" "F.Mask" "F.Paste")
			(net "P1V2_AUX")
		)
		(pad "N15" smd circle
			(at 1.199896 -0.40005 180)
			(size 0.4064 0.4064)
			(layers "F.Cu" "F.Mask" "F.Paste")
			(net "GND")
		)
		(pad "N16" smd circle
			(at 1.999996 -0.40005 180)
			(size 0.4064 0.4064)
			(layers "F.Cu" "F.Mask" "F.Paste")
			(net "GND")
		)
		(pad "N17" smd circle
			(at 2.800096 -0.40005 180)
			(size 0.4064 0.4064)
			(layers "F.Cu" "F.Mask" "F.Paste")
			(net "GND")
		)
		(pad "N18" smd circle
			(at 3.599942 -0.40005 180)
			(size 0.4064 0.4064)
			(layers "F.Cu" "F.Mask" "F.Paste")
			(net "GND")
		)
		(pad "N19" smd circle
			(at 4.400042 -0.40005 180)
			(size 0.4064 0.4064)
			(layers "F.Cu" "F.Mask" "F.Paste")
			(net "GND")
		)
		(pad "N21" smd circle
			(at 5.999988 -0.40005 180)
			(size 0.4064 0.4064)
			(layers "F.Cu" "F.Mask" "F.Paste")
			(net "P1V2_AUX")
		)
		(pad "N22" smd circle
			(at 6.800088 -0.40005 180)
			(size 0.4064 0.4064)
			(layers "F.Cu" "F.Mask" "F.Paste")
			(net "P3V3_AUX")
		)
		(pad "N23" smd circle
			(at 7.599934 -0.40005 180)
			(size 0.4064 0.4064)
			(layers "F.Cu" "F.Mask" "F.Paste")
			(net "LED_POSTCODE_1")
		)
		(pad "N24" smd circle
			(at 8.400034 -0.40005 180)
			(size 0.4064 0.4064)
			(layers "F.Cu" "F.Mask" "F.Paste")
			(net "LED_POSTCODE_3")
		)
		(pad "N25" smd circle
			(at 9.19988 -0.40005 180)
			(size 0.4064 0.4064)
			(layers "F.Cu" "F.Mask" "F.Paste")
			(net "LED_POSTCODE_2")
		)
		(pad "N26" smd circle
			(at 9.99998 -0.40005 180)
			(size 0.4064 0.4064)
			(layers "F.Cu" "F.Mask" "F.Paste")
			(net "LED_POSTCODE_6")
		)
		(pad "P1" smd circle
			(at -9.99998 0.40005 180)
			(size 0.4064 0.4064)
			(layers "F.Cu" "F.Mask" "F.Paste")
			(net "M_BMC_DDR4_DQ<5>")
		)
		(pad "P2" smd circle
			(at -9.19988 0.40005 180)
			(size 0.4064 0.4064)
			(layers "F.Cu" "F.Mask" "F.Paste")
			(net "M_BMC_DDR4_DQ<6>")
		)
		(pad "P3" smd circle
			(at -8.400034 0.40005 180)
			(size 0.4064 0.4064)
			(layers "F.Cu" "F.Mask" "F.Paste")
			(net "M_BMC_DDR4_DQ<7>")
		)
		(pad "P4" smd circle
			(at -7.599934 0.40005 180)
			(size 0.4064 0.4064)
			(layers "F.Cu" "F.Mask" "F.Paste")
			(net "GND")
		)
		(pad "P5" smd circle
			(at -6.800088 0.40005 180)
			(size 0.4064 0.4064)
			(layers "F.Cu" "F.Mask" "F.Paste")
			(net "IBMC_MIOZ")
		)
		(pad "P6" smd circle
			(at -5.999988 0.40005 180)
			(size 0.4064 0.4064)
			(layers "F.Cu" "F.Mask" "F.Paste")
			(net "P1V2_AUX")
		)
		(pad "P8" smd circle
			(at -4.400042 0.40005 180)
			(size 0.4064 0.4064)
			(layers "F.Cu" "F.Mask" "F.Paste")
			(net "P1V0_AUX")
		)
		(pad "P9" smd circle
			(at -3.599942 0.40005 180)
			(size 0.4064 0.4064)
			(layers "F.Cu" "F.Mask" "F.Paste")
			(net "GND")
		)
		(pad "P10" smd circle
			(at -2.800096 0.40005 180)
			(size 0.4064 0.4064)
			(layers "F.Cu" "F.Mask" "F.Paste")
			(net "GND")
		)
		(pad "P11" smd circle
			(at -1.999996 0.40005 180)
			(size 0.4064 0.4064)
			(layers "F.Cu" "F.Mask" "F.Paste")
			(net "P1V0_AUX")
		)
		(pad "P12" smd circle
			(at -1.199896 0.40005 180)
			(size 0.4064 0.4064)
			(layers "F.Cu" "F.Mask" "F.Paste")
			(net "P1V8_AUX")
		)
		(pad "P13" smd circle
			(at -0.40005 0.40005 180)
			(size 0.4064 0.4064)
			(layers "F.Cu" "F.Mask" "F.Paste")
			(net "P1V8_AUX")
		)
		(pad "P14" smd circle
			(at 0.40005 0.40005 180)
			(size 0.4064 0.4064)
			(layers "F.Cu" "F.Mask" "F.Paste")
			(net "P1V2_AUX")
		)
		(pad "P15" smd circle
			(at 1.199896 0.40005 180)
			(size 0.4064 0.4064)
			(layers "F.Cu" "F.Mask" "F.Paste")
			(net "GND")
		)
		(pad "P16" smd circle
			(at 1.999996 0.40005 180)
			(size 0.4064 0.4064)
			(layers "F.Cu" "F.Mask" "F.Paste")
			(net "GND")
		)
		(pad "P17" smd circle
			(at 2.800096 0.40005 180)
			(size 0.4064 0.4064)
			(layers "F.Cu" "F.Mask" "F.Paste")
			(net "GND")
		)
		(pad "P18" smd circle
			(at 3.599942 0.40005 180)
			(size 0.4064 0.4064)
			(layers "F.Cu" "F.Mask" "F.Paste")
			(net "GND")
		)
		(pad "P19" smd circle
			(at 4.400042 0.40005 180)
			(size 0.4064 0.4064)
			(layers "F.Cu" "F.Mask" "F.Paste")
			(net "GND")
		)
		(pad "P21" smd circle
			(at 5.999988 0.40005 180)
			(size 0.4064 0.4064)
			(layers "F.Cu" "F.Mask" "F.Paste")
			(net "P1V2_AUX")
		)
		(pad "P22" smd circle
			(at 6.800088 0.40005 180)
			(size 0.4064 0.4064)
			(layers "F.Cu" "F.Mask" "F.Paste")
			(net "P3V3_AUX")
		)
		(pad "P23" smd circle
			(at 7.599934 0.40005 180)
			(size 0.4064 0.4064)
			(layers "F.Cu" "F.Mask" "F.Paste")
			(net "RST_PCA9548_SENSOR_R_N")
		)
		(pad "P24" smd circle
			(at 8.400034 0.40005 180)
			(size 0.4064 0.4064)
			(layers "F.Cu" "F.Mask" "F.Paste")
			(net "H_CPU1_PROCHOT_LVC1_N")
		)
		(pad "P25" smd circle
			(at 9.19988 0.40005 180)
			(size 0.4064 0.4064)
			(layers "F.Cu" "F.Mask" "F.Paste")
			(net "LED_POSTCODE_0")
		)
		(pad "P26" smd circle
			(at 9.99998 0.40005 180)
			(size 0.4064 0.4064)
			(layers "F.Cu" "F.Mask" "F.Paste")
			(net "LED_POSTCODE_4")
		)
		(pad "R1" smd circle
			(at -9.99998 1.199896 180)
			(size 0.4064 0.4064)
			(layers "F.Cu" "F.Mask" "F.Paste")
			(net "M_BMC_DDR4_DQ<4>")
		)
		(pad "R2" smd circle
			(at -9.19988 1.199896 180)
			(size 0.4064 0.4064)
			(layers "F.Cu" "F.Mask" "F.Paste")
			(net "GND")
		)
		(pad "R3" smd circle
			(at -8.400034 1.199896 180)
			(size 0.4064 0.4064)
			(layers "F.Cu" "F.Mask" "F.Paste")
			(net "M_BMC_DDR4_DQ<3>")
		)
		(pad "R4" smd circle
			(at -7.599934 1.199896 180)
			(size 0.4064 0.4064)
			(layers "F.Cu" "F.Mask" "F.Paste")
			(net "M_BMC_DDR4_DQ<1>")
		)
		(pad "R5" smd circle
			(at -6.800088 1.199896 180)
			(size 0.4064 0.4064)
			(layers "F.Cu" "F.Mask" "F.Paste")
			(net "M_BMC_DDR4_MDM1")
		)
		(pad "R6" smd circle
			(at -5.999988 1.199896 180)
			(size 0.4064 0.4064)
			(layers "F.Cu" "F.Mask" "F.Paste")
			(net "P1V2_AUX")
		)
		(pad "R8" smd circle
			(at -4.400042 1.199896 180)
			(size 0.4064 0.4064)
			(layers "F.Cu" "F.Mask" "F.Paste")
			(net "GND")
		)
		(pad "R9" smd circle
			(at -3.599942 1.199896 180)
			(size 0.4064 0.4064)
			(layers "F.Cu" "F.Mask" "F.Paste")
			(net "P1V0_AUX")
		)
		(pad "R10" smd circle
			(at -2.800096 1.199896 180)
			(size 0.4064 0.4064)
			(layers "F.Cu" "F.Mask" "F.Paste")
			(net "P1V0_AUX")
		)
		(pad "R11" smd circle
			(at -1.999996 1.199896 180)
			(size 0.4064 0.4064)
			(layers "F.Cu" "F.Mask" "F.Paste")
			(net "GND")
		)
		(pad "R12" smd circle
			(at -1.199896 1.199896 180)
			(size 0.4064 0.4064)
			(layers "F.Cu" "F.Mask" "F.Paste")
			(net "P1V8_AUX")
		)
		(pad "R13" smd circle
			(at -0.40005 1.199896 180)
			(size 0.4064 0.4064)
			(layers "F.Cu" "F.Mask" "F.Paste")
			(net "P1V8_AUX")
		)
		(pad "R14" smd circle
			(at 0.40005 1.199896 180)
			(size 0.4064 0.4064)
			(layers "F.Cu" "F.Mask" "F.Paste")
			(net "P1V2_AUX")
		)
		(pad "R15" smd circle
			(at 1.199896 1.199896 180)
			(size 0.4064 0.4064)
			(layers "F.Cu" "F.Mask" "F.Paste")
			(net "GND")
		)
		(pad "R16" smd circle
			(at 1.999996 1.199896 180)
			(size 0.4064 0.4064)
			(layers "F.Cu" "F.Mask" "F.Paste")
			(net "GND")
		)
		(pad "R17" smd circle
			(at 2.800096 1.199896 180)
			(size 0.4064 0.4064)
			(layers "F.Cu" "F.Mask" "F.Paste")
			(net "GND")
		)
		(pad "R18" smd circle
			(at 3.599942 1.199896 180)
			(size 0.4064 0.4064)
			(layers "F.Cu" "F.Mask" "F.Paste")
			(net "GND")
		)
		(pad "R19" smd circle
			(at 4.400042 1.199896 180)
			(size 0.4064 0.4064)
			(layers "F.Cu" "F.Mask" "F.Paste")
			(net "GND")
		)
		(pad "R21" smd circle
			(at 5.999988 1.199896 180)
			(size 0.4064 0.4064)
			(layers "F.Cu" "F.Mask" "F.Paste")
			(net "P1V2_AUX")
		)
		(pad "R22" smd circle
			(at 6.800088 1.199896 180)
			(size 0.4064 0.4064)
			(layers "F.Cu" "F.Mask" "F.Paste")
			(net "P3V3_AUX")
		)
		(pad "R23" smd circle
			(at 7.599934 1.199896 180)
			(size 0.4064 0.4064)
			(layers "F.Cu" "F.Mask" "F.Paste")
			(net "IRQ_BMC_PCH_NMI_N")
		)
		(pad "R24" smd circle
			(at 8.400034 1.199896 180)
			(size 0.4064 0.4064)
			(layers "F.Cu" "F.Mask" "F.Paste")
			(net "FM_TPM_PRSNT_1_N")
		)
		(pad "R25" smd circle
			(at 9.19988 1.199896 180)
			(size 0.4064 0.4064)
			(layers "F.Cu" "F.Mask" "F.Paste")
			(net "GND")
		)
		(pad "R26" smd circle
			(at 9.99998 1.199896 180)
			(size 0.4064 0.4064)
			(layers "F.Cu" "F.Mask" "F.Paste")
			(net "FM_BMC_DEBUG_SW_N")
		)
		(pad "T1" smd circle
			(at -9.99998 1.999996 180)
			(size 0.4064 0.4064)
			(layers "F.Cu" "F.Mask" "F.Paste")
			(net "M_BMC_DDR4_DQS0_N")
		)
		(pad "T2" smd circle
			(at -9.19988 1.999996 180)
			(size 0.4064 0.4064)
			(layers "F.Cu" "F.Mask" "F.Paste")
			(net "M_BMC_DDR4_DQS0_P")
		)
		(pad "T3" smd circle
			(at -8.400034 1.999996 180)
			(size 0.4064 0.4064)
			(layers "F.Cu" "F.Mask" "F.Paste")
			(net "M_BMC_DDR4_DQ<0>")
		)
		(pad "T4" smd circle
			(at -7.599934 1.999996 180)
			(size 0.4064 0.4064)
			(layers "F.Cu" "F.Mask" "F.Paste")
			(net "GND")
		)
		(pad "T5" smd circle
			(at -6.800088 1.999996 180)
			(size 0.4064 0.4064)
			(layers "F.Cu" "F.Mask" "F.Paste")
			(net "P0V6_DDR_VREF_AUX")
		)
		(pad "T6" smd circle
			(at -5.999988 1.999996 180)
			(size 0.4064 0.4064)
			(layers "F.Cu" "F.Mask" "F.Paste")
			(net "P1V2_AUX")
		)
		(pad "T8" smd circle
			(at -4.400042 1.999996 180)
			(size 0.4064 0.4064)
			(layers "F.Cu" "F.Mask" "F.Paste")
			(net "P1V0_STBY_DP_VCC10A")
		)
		(pad "T9" smd circle
			(at -3.599942 1.999996 180)
			(size 0.4064 0.4064)
			(layers "F.Cu" "F.Mask" "F.Paste")
			(net "P1V0_STBY_PE_VCC10A")
		)
		(pad "T10" smd circle
			(at -2.800096 1.999996 180)
			(size 0.4064 0.4064)
			(layers "F.Cu" "F.Mask" "F.Paste")
			(net "P1V0_STBY_RC_VCC10A")
		)
		(pad "T11" smd circle
			(at -1.999996 1.999996 180)
			(size 0.4064 0.4064)
			(layers "F.Cu" "F.Mask" "F.Paste")
			(net "GND")
		)
		(pad "T12" smd circle
			(at -1.199896 1.999996 180)
			(size 0.4064 0.4064)
			(layers "F.Cu" "F.Mask" "F.Paste")
			(net "GND")
		)
		(pad "T13" smd circle
			(at -0.40005 1.999996 180)
			(size 0.4064 0.4064)
			(layers "F.Cu" "F.Mask" "F.Paste")
			(net "P1V8_AUX")
		)
		(pad "T14" smd circle
			(at 0.40005 1.999996 180)
			(size 0.4064 0.4064)
			(layers "F.Cu" "F.Mask" "F.Paste")
			(net "P1V2_AUX")
		)
		(pad "T15" smd circle
			(at 1.199896 1.999996 180)
			(size 0.4064 0.4064)
			(layers "F.Cu" "F.Mask" "F.Paste")
			(net "GND")
		)
		(pad "T16" smd circle
			(at 1.999996 1.999996 180)
			(size 0.4064 0.4064)
			(layers "F.Cu" "F.Mask" "F.Paste")
			(net "GND")
		)
		(pad "T17" smd circle
			(at 2.800096 1.999996 180)
			(size 0.4064 0.4064)
			(layers "F.Cu" "F.Mask" "F.Paste")
			(net "GND")
		)
		(pad "T18" smd circle
			(at 3.599942 1.999996 180)
			(size 0.4064 0.4064)
			(layers "F.Cu" "F.Mask" "F.Paste")
			(net "GND")
		)
		(pad "T19" smd circle
			(at 4.400042 1.999996 180)
			(size 0.4064 0.4064)
			(layers "F.Cu" "F.Mask" "F.Paste")
			(net "GND")
		)
		(pad "T21" smd circle
			(at 5.999988 1.999996 180)
			(size 0.4064 0.4064)
			(layers "F.Cu" "F.Mask" "F.Paste")
			(net "P1V2_AUX")
		)
		(pad "T22" smd circle
			(at 6.800088 1.999996 180)
			(size 0.4064 0.4064)
			(layers "F.Cu" "F.Mask" "F.Paste")
			(net "P3V3_AUX")
		)
		(pad "T23" smd circle
			(at 7.599934 1.999996 180)
			(size 0.4064 0.4064)
			(layers "F.Cu" "F.Mask" "F.Paste")
			(net "PWRGD_PCH_PWROK")
		)
		(pad "T24" smd circle
			(at 8.400034 1.999996 180)
			(size 0.4064 0.4064)
			(layers "F.Cu" "F.Mask" "F.Paste")
			(net "BMC_CPLD_GPIO_2_R1")
		)
		(pad "T25" smd circle
			(at 9.19988 1.999996 180)
			(size 0.4064 0.4064)
			(layers "F.Cu" "F.Mask" "F.Paste")
			(net "BMC_MONITER")
		)
		(pad "T26" smd circle
			(at 9.99998 1.999996 180)
			(size 0.4064 0.4064)
			(layers "F.Cu" "F.Mask" "F.Paste")
			(net "FM_THERMTRIP_DLY_LVC1_R_N")
		)
		(pad "U1" smd circle
			(at -9.99998 2.800096 180)
			(size 0.4064 0.4064)
			(layers "F.Cu" "F.Mask" "F.Paste")
			(net "M_BMC_DDR4_DQ<2>")
		)
		(pad "U2" smd circle
			(at -9.19988 2.800096 180)
			(size 0.4064 0.4064)
			(layers "F.Cu" "F.Mask" "F.Paste")
			(net "GND")
		)
		(pad "U3" smd circle
			(at -8.400034 2.800096 180)
			(size 0.4064 0.4064)
			(layers "F.Cu" "F.Mask" "F.Paste")
			(net "M_BMC_DDR4_DQ<15>")
		)
		(pad "U4" smd circle
			(at -7.599934 2.800096 180)
			(size 0.4064 0.4064)
			(layers "F.Cu" "F.Mask" "F.Paste")
			(net "M_BMC_DDR4_DQ<13>")
		)
		(pad "U5" smd circle
			(at -6.800088 2.800096 180)
			(size 0.4064 0.4064)
			(layers "F.Cu" "F.Mask" "F.Paste")
			(net "P0V6_DDR_VREF_AUX")
		)
		(pad "U6" smd circle
			(at -5.999988 2.800096 180)
			(size 0.4064 0.4064)
			(layers "F.Cu" "F.Mask" "F.Paste")
			(net "P1V8_AUX")
		)
		(pad "U8" smd circle
			(at -4.400042 2.800096 180)
			(size 0.4064 0.4064)
			(layers "F.Cu" "F.Mask" "F.Paste")
			(net "GND")
		)
		(pad "U9" smd circle
			(at -3.599942 2.800096 180)
			(size 0.4064 0.4064)
			(layers "F.Cu" "F.Mask" "F.Paste")
			(net "GND")
		)
		(pad "U10" smd circle
			(at -2.800096 2.800096 180)
			(size 0.4064 0.4064)
			(layers "F.Cu" "F.Mask" "F.Paste")
			(net "GND")
		)
		(pad "U11" smd circle
			(at -1.999996 2.800096 180)
			(size 0.4064 0.4064)
			(layers "F.Cu" "F.Mask" "F.Paste")
			(net "GND")
		)
		(pad "U12" smd circle
			(at -1.199896 2.800096 180)
			(size 0.4064 0.4064)
			(layers "F.Cu" "F.Mask" "F.Paste")
			(net "GND")
		)
		(pad "U13" smd circle
			(at -0.40005 2.800096 180)
			(size 0.4064 0.4064)
			(layers "F.Cu" "F.Mask" "F.Paste")
			(net "P1V8_AUX")
		)
		(pad "U14" smd circle
			(at 0.40005 2.800096 180)
			(size 0.4064 0.4064)
			(layers "F.Cu" "F.Mask" "F.Paste")
			(net "GND")
		)
		(pad "U15" smd circle
			(at 1.199896 2.800096 180)
			(size 0.4064 0.4064)
			(layers "F.Cu" "F.Mask" "F.Paste")
			(net "P1V2_AUX")
		)
		(pad "U16" smd circle
			(at 1.999996 2.800096 180)
			(size 0.4064 0.4064)
			(layers "F.Cu" "F.Mask" "F.Paste")
			(net "P1V2_AUX")
		)
		(pad "U17" smd circle
			(at 2.800096 2.800096 180)
			(size 0.4064 0.4064)
			(layers "F.Cu" "F.Mask" "F.Paste")
			(net "P1V2_AUX")
		)
		(pad "U18" smd circle
			(at 3.599942 2.800096 180)
			(size 0.4064 0.4064)
			(layers "F.Cu" "F.Mask" "F.Paste")
			(net "P1V2_AUX")
		)
		(pad "U19" smd circle
			(at 4.400042 2.800096 180)
			(size 0.4064 0.4064)
			(layers "F.Cu" "F.Mask" "F.Paste")
			(net "GND")
		)
		(pad "U21" smd circle
			(at 5.999988 2.800096 180)
			(size 0.4064 0.4064)
			(layers "F.Cu" "F.Mask" "F.Paste")
			(net "P1V2_P1V0_I3C_VDDL2")
		)
		(pad "U22" smd circle
			(at 6.800088 2.800096 180)
			(size 0.4064 0.4064)
			(layers "F.Cu" "F.Mask" "F.Paste")
			(net "GND")
		)
		(pad "U23" smd circle
			(at 7.599934 2.800096 180)
			(size 0.4064 0.4064)
			(layers "F.Cu" "F.Mask" "F.Paste")
			(net "GND")
		)
		(pad "U24" smd circle
			(at 8.400034 2.800096 180)
			(size 0.4064 0.4064)
			(layers "F.Cu" "F.Mask" "F.Paste")
			(net "IRQ_UV_DETECT_N")
		)
	)
)
